(kicad_pcb
	(version 20241229)
	(generator "pcbnew")
	(generator_version "9.0")
	(general
		(thickness 1.62)
		(legacy_teardrops no)
	)
	(paper "A3")
	(title_block
		(title "COM Express 7 Baseboard")
		(date "2025-02-04")
		(rev "1.1.2")
		(company "Antmicro Ltd")
		(comment 1 "www.antmicro.com")
		(comment 9 "footprints 340-344 of 802")
	)
	(layers
		(0 "F.Cu" signal)
		(4 "In1.Cu" signal)
		(6 "In2.Cu" signal)
		(8 "In3.Cu" signal)
		(10 "In4.Cu" signal)
		(12 "In5.Cu" signal)
		(14 "In6.Cu" signal)
		(2 "B.Cu" signal)
		(9 "F.Adhes" user "F.Adhesive")
		(11 "B.Adhes" user "B.Adhesive")
		(13 "F.Paste" user)
		(15 "B.Paste" user)
		(5 "F.SilkS" user "F.Silkscreen")
		(7 "B.SilkS" user "B.Silkscreen")
		(1 "F.Mask" user)
		(3 "B.Mask" user)
		(17 "Dwgs.User" user "User.Drawings")
		(19 "Cmts.User" user "User.Comments")
		(21 "Eco1.User" user "User.Eco1")
		(23 "Eco2.User" user "User.Eco2")
		(25 "Edge.Cuts" user)
		(27 "Margin" user)
		(31 "F.CrtYd" user "F.Courtyard")
		(29 "B.CrtYd" user "B.Courtyard")
		(35 "F.Fab" user)
		(33 "B.Fab" user)
	)
	(footprint "antmicro-footprints:MS621FE-FL11E"
		(layer "F.Cu")
		(at 314.2 72.81 90)
		(property "Reference" "BT1"
			(at 1.3 -5.05 180)
			(layer "F.SilkS")
			(effects
				(font
					(size 0.7 0.7)
					(thickness 0.15)
				)
				(justify left bottom)
			)
		)
		(property "Value" "Battery_Holder_MS621FE-FL11E"
			(at -0.001 6.2 90)
			(layer "F.Fab")
			(effects
				(font
					(size 0.7 0.7)
					(thickness 0.15)
				)
				(justify left bottom)
			)
		)
		(property "Datasheet" "https://www.sii.co.jp/en/me/datasheets/ms-rechargeable/ms621fe/"
			(at 0 0 90)
			(layer "F.Fab")
			(hide yes)
			(effects
				(font
					(size 1.27 1.27)
					(thickness 0.15)
				)
			)
		)
		(property "Author" "Antmicro"
			(at 387.01 -241.39 0)
			(layer "F.Fab")
			(hide yes)
			(effects
				(font
					(size 1 1)
					(thickness 0.15)
				)
			)
		)
		(property "License" "Apache-2.0"
			(at 387.01 -241.39 0)
			(layer "F.Fab")
			(hide yes)
			(effects
				(font
					(size 1 1)
					(thickness 0.15)
				)
			)
		)
		(property "MPN" "MS621FE-FL11E"
			(at 387.01 -241.39 0)
			(layer "F.Fab")
			(hide yes)
			(effects
				(font
					(size 1 1)
					(thickness 0.15)
				)
			)
		)
		(property "Manufacturer" "Seiko Instruments"
			(at 387.01 -241.39 0)
			(layer "F.Fab")
			(hide yes)
			(effects
				(font
					(size 1 1)
					(thickness 0.15)
				)
			)
		)
		(sheetname "Com Express 7 MGMT")
		(sheetfile "com_express_7_mgmt.kicad_sch")
		(attr smd)
		(fp_arc
			(start 1.2 -2.15)
			(mid 0 4.834)
			(end -1.2 -2.15)
			(stroke
				(width 0.15)
				(type solid)
			)
			(layer "F.SilkS")
		)
		(fp_line
			(start 1.275 -5.2)
			(end -1.275 -5.2)
			(stroke
				(width 0.05)
				(type solid)
			)
			(layer "F.CrtYd")
		)
		(fp_line
			(start 1.275 -5.2)
			(end 1.275 -2.425)
			(stroke
				(width 0.05)
				(type solid)
			)
			(layer "F.CrtYd")
		)
		(fp_line
			(start -1.275 -5.2)
			(end -1.275 -2.425)
			(stroke
				(width 0.05)
				(type solid)
			)
			(layer "F.CrtYd")
		)
		(fp_arc
			(start 1.275 -2.425)
			(mid 0 5.143374)
			(end -1.275 -2.425)
			(stroke
				(width 0.05)
				(type solid)
			)
			(layer "F.CrtYd")
		)
		(fp_line
			(start 1.2 -5.05)
			(end -0.8 -5.05)
			(stroke
				(width 0.15)
				(type solid)
			)
			(layer "F.Fab")
		)
		(fp_line
			(start 1.2 -5.05)
			(end 1.2 -2.04)
			(stroke
				(width 0.15)
				(type solid)
			)
			(layer "F.Fab")
		)
		(fp_line
			(start -0.8 -5.05)
			(end -1.2 -4.65)
			(stroke
				(width 0.15)
				(type solid)
			)
			(layer "F.Fab")
		)
		(fp_line
			(start -1.2 -4.65)
			(end -1.2 -2.04)
			(stroke
				(width 0.15)
				(type solid)
			)
			(layer "F.Fab")
		)
		(fp_circle
			(center -0.001 1.25)
			(end -0.001 -2.25)
			(stroke
				(width 0.15)
				(type solid)
			)
			(fill no)
			(layer "F.Fab")
		)
		(fp_text user "COPPER KEEPOUT"
			(at -0.2 -3.14 0)
			(unlocked yes)
			(layer "F.Fab")
			(effects
				(font
					(size 0.4 0.4)
					(thickness 0.1)
				)
				(justify left bottom)
			)
		)
		(pad "1" smd rect
			(at -0.75 -4.05)
			(size 1.8 0.75)
			(layers "F.Cu" "F.Mask" "F.Paste")
			(net 41 "Net-(BT1-+)")
			(pinfunction "+")
			(pintype "passive")
			(teardrops
				(best_length_ratio 0.2)
				(max_length 1)
				(best_width_ratio 0.9)
				(max_width 2)
				(curved_edges yes)
				(filter_ratio 0.9)
				(enabled yes)
				(allow_two_segments yes)
				(prefer_zone_connections yes)
			)
		)
		(pad "2" smd rect
			(at 0.75 -4.05)
			(size 1.8 0.75)
			(layers "F.Cu" "F.Mask" "F.Paste")
			(net 1 "GND")
			(pinfunction "-")
			(pintype "passive")
			(teardrops
				(best_length_ratio 0.2)
				(max_length 1)
				(best_width_ratio 0.9)
				(max_width 2)
				(curved_edges yes)
				(filter_ratio 0.9)
				(enabled yes)
				(allow_two_segments yes)
				(prefer_zone_connections yes)
			)
		)
		(zone
			(net 0)
			(net_name "")
			(layers "F.Cu" "F.CrtYd")
			(hatch edge 0.508)
			(connect_pads
				(clearance 0)
			)
			(min_thickness 0.254)
			(filled_areas_thickness no)
			(keepout
				(tracks allowed)
				(vias not_allowed)
				(pads not_allowed)
				(copperpour not_allowed)
				(footprints allowed)
			)
			(placement
				(enabled no)
				(sheetname "")
			)
			(fill
				(thermal_gap 0.508)
				(thermal_bridge_width 0.508)
			)
			(polygon
				(pts
					(xy 316.7 73.97) (xy 311.06 73.97) (xy 311.06 71.65) (xy 316.7 71.65)
				)
			)
		)
	)
	(footprint "antmicro-footprints:C_0402_1005Metric"
		(layer "F.Cu")
		(at 130.9 81.760001 -90)
		(descr "Capacitor SMD 0402")
		(tags "capacitor SMD 0402")
		(property "Reference" "C147"
			(at -3.650001 -0.4 90)
			(layer "F.SilkS")
			(effects
				(font
					(size 0.7 0.7)
					(thickness 0.15)
				)
				(justify right bottom)
			)
		)
		(property "Value" "C_100n_0402"
			(at -1.022927 2.155213 90)
			(layer "F.Fab")
			(effects
				(font
					(size 0.7 0.7)
					(thickness 0.15)
				)
				(justify right bottom)
			)
		)
		(property "Datasheet" "https://www.murata.com/products/productdetail?partno=GRM155R61H104KE14%23"
			(at 0 0 270)
			(layer "F.Fab")
			(hide yes)
			(effects
				(font
					(size 1.27 1.27)
					(thickness 0.15)
				)
			)
		)
		(property "Author" "Antmicro"
			(at 49.139999 212.660001 0)
			(layer "F.Fab")
			(hide yes)
			(effects
				(font
					(size 1 1)
					(thickness 0.15)
				)
			)
		)
		(property "Dielectric" "X5R"
			(at 49.139999 212.660001 0)
			(layer "F.Fab")
			(hide yes)
			(effects
				(font
					(size 1 1)
					(thickness 0.15)
				)
			)
		)
		(property "License" "Apache-2.0"
			(at 49.139999 212.660001 0)
			(layer "F.Fab")
			(hide yes)
			(effects
				(font
					(size 1 1)
					(thickness 0.15)
				)
			)
		)
		(property "MPN" "GRM155R61H104KE14D"
			(at 49.139999 212.660001 0)
			(layer "F.Fab")
			(hide yes)
			(effects
				(font
					(size 1 1)
					(thickness 0.15)
				)
			)
		)
		(property "Manufacturer" "Murata"
			(at 49.139999 212.660001 0)
			(layer "F.Fab")
			(hide yes)
			(effects
				(font
					(size 1 1)
					(thickness 0.15)
				)
			)
		)
		(property "Public" "False"
			(at 49.139999 212.660001 0)
			(layer "F.Fab")
			(hide yes)
			(effects
				(font
					(size 1 1)
					(thickness 0.15)
				)
			)
		)
		(property "Val" "100n"
			(at 49.139999 212.660001 0)
			(layer "F.Fab")
			(hide yes)
			(effects
				(font
					(size 1 1)
					(thickness 0.15)
				)
			)
		)
		(property "Voltage" "50V"
			(at 49.139999 212.660001 0)
			(layer "F.Fab")
			(hide yes)
			(effects
				(font
					(size 1 1)
					(thickness 0.15)
				)
			)
		)
		(sheetname "GPIO expander")
		(sheetfile "gpio_exp.kicad_sch")
		(attr smd)
		(fp_rect
			(start -0.925 -0.47)
			(end 0.925 0.47)
			(stroke
				(width 0.05)
				(type default)
			)
			(fill no)
			(layer "F.CrtYd")
		)
		(fp_line
			(start -0.494 0.248)
			(end -0.494 -0.25)
			(stroke
				(width 0.15)
				(type solid)
			)
			(layer "F.Fab")
		)
		(fp_line
			(start 0.504 0.248)
			(end -0.494 0.248)
			(stroke
				(width 0.15)
				(type solid)
			)
			(layer "F.Fab")
		)
		(fp_line
			(start -0.494 -0.25)
			(end 0.504 -0.25)
			(stroke
				(width 0.15)
				(type solid)
			)
			(layer "F.Fab")
		)
		(fp_line
			(start 0.504 -0.25)
			(end 0.504 0.248)
			(stroke
				(width 0.15)
				(type solid)
			)
			(layer "F.Fab")
		)
		(pad "1" smd roundrect
			(at -0.48 0 270)
			(size 0.59 0.64)
			(layers "F.Cu" "F.Mask" "F.Paste")
			(roundrect_rratio 0.25)
			(net 1 "GND")
			(pintype "passive")
			(teardrops
				(best_length_ratio 0.2)
				(max_length 1)
				(best_width_ratio 0.9)
				(max_width 2)
				(curved_edges yes)
				(filter_ratio 0.9)
				(enabled yes)
				(allow_two_segments yes)
				(prefer_zone_connections yes)
			)
		)
		(pad "2" smd roundrect
			(at 0.48 0 270)
			(size 0.59 0.64)
			(layers "F.Cu" "F.Mask" "F.Paste")
			(roundrect_rratio 0.25)
			(net 2 "+3V3")
			(pintype "passive")
			(teardrops
				(best_length_ratio 0.2)
				(max_length 1)
				(best_width_ratio 0.9)
				(max_width 2)
				(curved_edges yes)
				(filter_ratio 0.9)
				(enabled yes)
				(allow_two_segments yes)
				(prefer_zone_connections yes)
			)
		)
	)
	(footprint "antmicro-footprints:R_0402_1005Metric"
		(layer "F.Cu")
		(at 258.12 161.08 -90)
		(descr "Resistor SMD 0402")
		(tags "resistor SMD 0402")
		(property "Reference" "R181"
			(at -3.65 -0.45 90)
			(layer "F.SilkS")
			(effects
				(font
					(size 0.7 0.7)
					(thickness 0.15)
				)
				(justify right bottom)
			)
		)
		(property "Value" "R_1k_0402"
			(at -1.011843 1.772046 90)
			(layer "F.Fab")
			(effects
				(font
					(size 0.7 0.7)
					(thickness 0.15)
				)
				(justify right bottom)
			)
		)
		(property "Datasheet" "https://www.bourns.com/docs/product-datasheets/cr.pdf"
			(at 0 0 90)
			(layer "F.Fab")
			(hide yes)
			(effects
				(font
					(size 1.27 1.27)
					(thickness 0.15)
				)
			)
		)
		(property "Author" "Antmicro"
			(at 337.8 291.82 90)
			(layer "F.Fab")
			(hide yes)
			(effects
				(font
					(size 1 1)
					(thickness 0.15)
				)
			)
		)
		(property "License" "Apache-2.0"
			(at 337.8 291.82 90)
			(layer "F.Fab")
			(hide yes)
			(effects
				(font
					(size 1 1)
					(thickness 0.15)
				)
			)
		)
		(property "MPN" "CR0402-FX-1001GLF"
			(at 337.8 291.82 90)
			(layer "F.Fab")
			(hide yes)
			(effects
				(font
					(size 1 1)
					(thickness 0.15)
				)
			)
		)
		(property "Manufacturer" "Bourns"
			(at 337.8 291.82 90)
			(layer "F.Fab")
			(hide yes)
			(effects
				(font
					(size 1 1)
					(thickness 0.15)
				)
			)
		)
		(property "Public" "False"
			(at 337.8 291.82 90)
			(layer "F.Fab")
			(hide yes)
			(effects
				(font
					(size 1 1)
					(thickness 0.15)
				)
			)
		)
		(property "Tolerance" "1%"
			(at 337.8 291.82 90)
			(layer "F.Fab")
			(hide yes)
			(effects
				(font
					(size 1 1)
					(thickness 0.15)
				)
			)
		)
		(property "Val" "1k"
			(at 337.8 291.82 90)
			(layer "F.Fab")
			(hide yes)
			(effects
				(font
					(size 1 1)
					(thickness 0.15)
				)
			)
		)
		(sheetname "Com Express 7 MGMT")
		(sheetfile "com_express_7_mgmt.kicad_sch")
		(attr smd)
		(fp_rect
			(start -0.925 -0.47)
			(end 0.925 0.47)
			(stroke
				(width 0.05)
				(type default)
			)
			(fill no)
			(layer "F.CrtYd")
		)
		(fp_rect
			(start -0.5 -0.25)
			(end 0.5 0.25)
			(stroke
				(width 0.15)
				(type solid)
			)
			(fill no)
			(layer "F.Fab")
		)
		(pad "1" smd roundrect
			(at -0.48 0 270)
			(size 0.59 0.64)
			(layers "F.Cu" "F.Mask" "F.Paste")
			(roundrect_rratio 0.25)
			(net 601 "Net-(U36-~{WP}(D2))")
			(pintype "passive")
			(teardrops
				(best_length_ratio 0.2)
				(max_length 1)
				(best_width_ratio 0.9)
				(max_width 2)
				(curved_edges yes)
				(filter_ratio 0.9)
				(enabled yes)
				(allow_two_segments yes)
				(prefer_zone_connections yes)
			)
		)
		(pad "2" smd roundrect
			(at 0.48 0 270)
			(size 0.59 0.64)
			(layers "F.Cu" "F.Mask" "F.Paste")
			(roundrect_rratio 0.25)
			(net 85 "/Com Express 7 MGMT/MAFS_POWER")
			(pintype "passive")
			(teardrops
				(best_length_ratio 0.2)
				(max_length 1)
				(best_width_ratio 0.9)
				(max_width 2)
				(curved_edges yes)
				(filter_ratio 0.9)
				(enabled yes)
				(allow_two_segments yes)
				(prefer_zone_connections yes)
			)
		)
	)
	(footprint "antmicro-footprints:C_0402_1005Metric"
		(layer "F.Cu")
		(at 112.15 134.56 180)
		(descr "Capacitor SMD 0402")
		(tags "capacitor SMD 0402")
		(property "Reference" "C202"
			(at -3.85 -0.55 0)
			(layer "F.SilkS")
			(effects
				(font
					(size 0.7 0.7)
					(thickness 0.15)
				)
				(justify right bottom)
			)
		)
		(property "Value" "C_100n_0402"
			(at -1.022927 2.155213 0)
			(layer "F.Fab")
			(effects
				(font
					(size 0.7 0.7)
					(thickness 0.15)
				)
				(justify right bottom)
			)
		)
		(property "Datasheet" "https://www.murata.com/products/productdetail?partno=GRM155R61H104KE14%23"
			(at 0 0 180)
			(layer "F.Fab")
			(hide yes)
			(effects
				(font
					(size 1.27 1.27)
					(thickness 0.15)
				)
			)
		)
		(property "Author" "Antmicro"
			(at 224.3 269.12 0)
			(layer "F.Fab")
			(hide yes)
			(effects
				(font
					(size 1 1)
					(thickness 0.15)
				)
			)
		)
		(property "Dielectric" "X5R"
			(at 224.3 269.12 0)
			(layer "F.Fab")
			(hide yes)
			(effects
				(font
					(size 1 1)
					(thickness 0.15)
				)
			)
		)
		(property "License" "Apache-2.0"
			(at 224.3 269.12 0)
			(layer "F.Fab")
			(hide yes)
			(effects
				(font
					(size 1 1)
					(thickness 0.15)
				)
			)
		)
		(property "MPN" "GRM155R61H104KE14D"
			(at 224.3 269.12 0)
			(layer "F.Fab")
			(hide yes)
			(effects
				(font
					(size 1 1)
					(thickness 0.15)
				)
			)
		)
		(property "Manufacturer" "Murata"
			(at 224.3 269.12 0)
			(layer "F.Fab")
			(hide yes)
			(effects
				(font
					(size 1 1)
					(thickness 0.15)
				)
			)
		)
		(property "Public" "False"
			(at 224.3 269.12 0)
			(layer "F.Fab")
			(hide yes)
			(effects
				(font
					(size 1 1)
					(thickness 0.15)
				)
			)
		)
		(property "Val" "100n"
			(at 224.3 269.12 0)
			(layer "F.Fab")
			(hide yes)
			(effects
				(font
					(size 1 1)
					(thickness 0.15)
				)
			)
		)
		(property "Voltage" "50V"
			(at 224.3 269.12 0)
			(layer "F.Fab")
			(hide yes)
			(effects
				(font
					(size 1 1)
					(thickness 0.15)
				)
			)
		)
		(sheetname "SD card")
		(sheetfile "sd_card.kicad_sch")
		(attr smd)
		(fp_rect
			(start -0.925 -0.47)
			(end 0.925 0.47)
			(stroke
				(width 0.05)
				(type default)
			)
			(fill no)
			(layer "F.CrtYd")
		)
		(fp_line
			(start 0.504 0.248)
			(end -0.494 0.248)
			(stroke
				(width 0.15)
				(type solid)
			)
			(layer "F.Fab")
		)
		(fp_line
			(start 0.504 -0.25)
			(end 0.504 0.248)
			(stroke
				(width 0.15)
				(type solid)
			)
			(layer "F.Fab")
		)
		(fp_line
			(start -0.494 0.248)
			(end -0.494 -0.25)
			(stroke
				(width 0.15)
				(type solid)
			)
			(layer "F.Fab")
		)
		(fp_line
			(start -0.494 -0.25)
			(end 0.504 -0.25)
			(stroke
				(width 0.15)
				(type solid)
			)
			(layer "F.Fab")
		)
		(pad "1" smd roundrect
			(at -0.48 0 180)
			(size 0.59 0.64)
			(layers "F.Cu" "F.Mask" "F.Paste")
			(roundrect_rratio 0.25)
			(net 1 "GND")
			(pintype "passive")
			(teardrops
				(best_length_ratio 0.2)
				(max_length 1)
				(best_width_ratio 0.9)
				(max_width 2)
				(curved_edges yes)
				(filter_ratio 0.9)
				(enabled yes)
				(allow_two_segments yes)
				(prefer_zone_connections yes)
			)
		)
		(pad "2" smd roundrect
			(at 0.48 0 180)
			(size 0.59 0.64)
			(layers "F.Cu" "F.Mask" "F.Paste")
			(roundrect_rratio 0.25)
			(net 2 "+3V3")
			(pintype "passive")
			(teardrops
				(best_length_ratio 0.2)
				(max_length 1)
				(best_width_ratio 0.9)
				(max_width 2)
				(curved_edges yes)
				(filter_ratio 0.9)
				(enabled yes)
				(allow_two_segments yes)
				(prefer_zone_connections yes)
			)
		)
	)
	(footprint "antmicro-footprints:TP_SMD_0.75mm"
		(layer "F.Cu")
		(at 127.14 128.71)
		(property "Reference" "TP77"
			(at 0.46 -3.3 90)
			(layer "F.SilkS")
			(effects
				(font
					(size 0.7 0.7)
					(thickness 0.15)
				)
				(justify left bottom)
			)
		)
		(property "Value" "TP_0.75mm_SMD"
			(at 0 1.2 0)
			(layer "F.Fab")
			(effects
				(font
					(size 0.7 0.7)
					(thickness 0.15)
				)
				(justify left bottom)
			)
		)
		(property "Author" "Antmicro"
			(at 0 0 0)
			(layer "F.Fab")
			(hide yes)
			(effects
				(font
					(size 1 1)
					(thickness 0.15)
				)
			)
		)
		(property "License" "Apache-2.0"
			(at 0 0 0)
			(layer "F.Fab")
			(hide yes)
			(effects
				(font
					(size 1 1)
					(thickness 0.15)
				)
			)
		)
		(property "MPN" ""
			(at 0 0 0)
			(layer "F.Fab")
			(hide yes)
			(effects
				(font
					(size 1 1)
					(thickness 0.15)
				)
			)
		)
		(property "Manufacturer" ""
			(at 0 0 0)
			(layer "F.Fab")
			(hide yes)
			(effects
				(font
					(size 1 1)
					(thickness 0.15)
				)
			)
		)
		(property "Public" "False"
			(at 0 0 0)
			(layer "F.Fab")
			(hide yes)
			(effects
				(font
					(size 1 1)
					(thickness 0.15)
				)
			)
		)
		(sheetname "KR to SFI #2")
		(sheetfile "kr_sfi.kicad_sch")
		(attr exclude_from_pos_files exclude_from_bom)
		(fp_circle
			(center 0 0)
			(end 0.475 0)
			(stroke
				(width 0.05)
				(type default)
			)
			(fill no)
			(layer "F.CrtYd")
		)
		(pad "1" smd circle
			(at 0 0)
			(size 0.75 0.75)
			(layers "F.Cu" "F.Mask")
			(net 740 "Net-(U45C-REFCLK1+)")
			(pinfunction "1")
			(pintype "passive")
			(teardrops
				(best_length_ratio 0.4)
				(max_length 1)
				(best_width_ratio 0.9)
				(max_width 2)
				(curved_edges yes)
				(filter_ratio 0.9)
				(enabled yes)
				(allow_two_segments yes)
				(prefer_zone_connections yes)
			)
		)
	)
)
